(kicad_pcb
	(version 20260206)
	(generator "pcbnew")
	(generator_version "10.0")
	(general
		(thickness 1.6)
		(legacy_teardrops no)
	)
	(paper "A4")
	(title_block
		(title "03242023_DA0F0TMBIJ0_F0T_Motherboard_J_brd_V01_OCP.brd")
		(comment 1 "Grand Teton / footprints 140-146 of 6105")
	)
	(layers
		(0 "F.Cu" signal "TOP")
		(4 "In1.Cu" signal "GND")
		(6 "In2.Cu" signal "IN1")
		(8 "In3.Cu" signal "GND1")
		(10 "In4.Cu" signal "IN2")
		(12 "In5.Cu" signal "GND2")
		(14 "In6.Cu" signal "IN3")
		(16 "In7.Cu" signal "GND3")
		(18 "In8.Cu" signal "VCC")
		(20 "In9.Cu" signal "VCC1")
		(22 "In10.Cu" signal "GND4")
		(24 "In11.Cu" signal "IN4")
		(26 "In12.Cu" signal "GND5")
		(28 "In13.Cu" signal "IN5")
		(30 "In14.Cu" signal "GND6")
		(32 "In15.Cu" signal "IN6")
		(34 "In16.Cu" signal "GND7")
		(2 "B.Cu" signal "BOTTOM")
		(9 "F.Adhes" user "F.Adhesive")
		(11 "B.Adhes" user "B.Adhesive")
		(13 "F.Paste" user "Package Geometry/Pastemask Top")
		(15 "B.Paste" user "Package Geometry/Pastemask Bottom")
		(5 "F.SilkS" user "Ref Des/Silkscreen Top")
		(7 "B.SilkS" user "Ref Des/Silkscreen Bottom")
		(1 "F.Mask" user "Board Geometry/Soldermask Top")
		(3 "B.Mask" user "Board Geometry/Soldermask Bottom")
		(17 "Dwgs.User" user "User.Drawings")
		(19 "Cmts.User" user "User.Comments")
		(21 "Eco1.User" user "User.Eco1")
		(23 "Eco2.User" user "User.Eco2")
		(25 "Edge.Cuts" user "Board Geometry/Outline")
		(27 "Margin" user)
		(31 "F.CrtYd" user "Package Geometry/Place Bound Top")
		(29 "B.CrtYd" user "Package Geometry/Place Bound Bottom")
		(35 "F.Fab" user "Ref Des/Assembly Top")
		(33 "B.Fab" user "Ref Des/Assembly Bottom")
	)
	(footprint ""
		(layer "F.Cu")
		(at 60.527438 -31.887922 -90)
		(property "Reference" "R3867"
			(at 0 0 270)
			(layer "F.SilkS")
			(hide yes)
			(effects
				(font
					(size 1.27 1.27)
				)
			)
		)
		(property "Value" ""
			(at 0 0 270)
			(layer "F.Fab")
			(effects
				(font
					(size 1.27 1.27)
				)
			)
		)
		(duplicate_pad_numbers_are_jumpers no)
		(fp_line
			(start -0.7874 0.4064)
			(end -0.7874 -0.4064)
			(stroke
				(width 0.1524)
				(type default)
			)
			(layer "F.SilkS")
		)
		(fp_line
			(start 0.7874 0.4064)
			(end -0.7874 0.4064)
			(stroke
				(width 0.1524)
				(type default)
			)
			(layer "F.SilkS")
		)
		(fp_line
			(start -0.7874 -0.4064)
			(end 0.7874 -0.4064)
			(stroke
				(width 0.1524)
				(type default)
			)
			(layer "F.SilkS")
		)
		(fp_line
			(start 0.7874 -0.4064)
			(end 0.7874 0.4064)
			(stroke
				(width 0.1524)
				(type default)
			)
			(layer "F.SilkS")
		)
		(fp_line
			(start -0.67945 0.3048)
			(end -0.67945 -0.305054)
			(stroke
				(width 0.1)
				(type default)
			)
			(layer "F.Fab")
		)
		(fp_line
			(start -0.12065 0.3048)
			(end -0.67945 0.3048)
			(stroke
				(width 0.1)
				(type default)
			)
			(layer "F.Fab")
		)
		(fp_line
			(start 0.120396 0.3048)
			(end 0.120396 0.2794)
			(stroke
				(width 0.1)
				(type default)
			)
			(layer "F.Fab")
		)
		(fp_line
			(start 0.67945 0.3048)
			(end 0.120396 0.3048)
			(stroke
				(width 0.1)
				(type default)
			)
			(layer "F.Fab")
		)
		(fp_line
			(start -0.12065 0.2794)
			(end -0.12065 0.3048)
			(stroke
				(width 0.1)
				(type default)
			)
			(layer "F.Fab")
		)
		(fp_line
			(start 0.120396 0.2794)
			(end -0.12065 0.2794)
			(stroke
				(width 0.1)
				(type default)
			)
			(layer "F.Fab")
		)
		(fp_line
			(start -0.12065 -0.2794)
			(end 0.12065 -0.2794)
			(stroke
				(width 0.1)
				(type default)
			)
			(layer "F.Fab")
		)
		(fp_line
			(start 0.12065 -0.2794)
			(end 0.12065 -0.3048)
			(stroke
				(width 0.1)
				(type default)
			)
			(layer "F.Fab")
		)
		(fp_line
			(start 0.12065 -0.3048)
			(end 0.67945 -0.3048)
			(stroke
				(width 0.1)
				(type default)
			)
			(layer "F.Fab")
		)
		(fp_line
			(start 0.67945 -0.3048)
			(end 0.67945 0.3048)
			(stroke
				(width 0.1)
				(type default)
			)
			(layer "F.Fab")
		)
		(fp_line
			(start -0.67945 -0.305054)
			(end -0.12065 -0.305054)
			(stroke
				(width 0.1)
				(type default)
			)
			(layer "F.Fab")
		)
		(fp_line
			(start -0.12065 -0.305054)
			(end -0.12065 -0.2794)
			(stroke
				(width 0.1)
				(type default)
			)
			(layer "F.Fab")
		)
		(pad "1" smd rect
			(at -0.40005 0 90)
			(size 0.4572 0.508)
			(layers "F.Cu" "F.Mask" "F.Paste")
			(net "P12V_OCP_SENSE_2")
		)
		(pad "2" smd rect
			(at 0.40005 0 90)
			(size 0.4572 0.508)
			(layers "F.Cu" "F.Mask" "F.Paste")
			(net "P12V_OCP_V3_2_ISENSE_MAM_MAM")
		)
	)
	(footprint ""
		(layer "F.Cu")
		(at 130.73888 -92.674948 90)
		(property "Reference" "R4405"
			(at 0 0 90)
			(layer "F.SilkS")
			(hide yes)
			(effects
				(font
					(size 1.27 1.27)
				)
			)
		)
		(property "Value" ""
			(at 0 0 90)
			(layer "F.Fab")
			(effects
				(font
					(size 1.27 1.27)
				)
			)
		)
		(duplicate_pad_numbers_are_jumpers no)
		(fp_line
			(start 0.7874 -0.4064)
			(end 0.7874 0.4064)
			(stroke
				(width 0.1524)
				(type default)
			)
			(layer "F.SilkS")
		)
		(fp_line
			(start -0.7874 -0.4064)
			(end 0.7874 -0.4064)
			(stroke
				(width 0.1524)
				(type default)
			)
			(layer "F.SilkS")
		)
		(fp_line
			(start 0.7874 0.4064)
			(end -0.7874 0.4064)
			(stroke
				(width 0.1524)
				(type default)
			)
			(layer "F.SilkS")
		)
		(fp_line
			(start -0.7874 0.4064)
			(end -0.7874 -0.4064)
			(stroke
				(width 0.1524)
				(type default)
			)
			(layer "F.SilkS")
		)
		(fp_line
			(start -0.12065 -0.305054)
			(end -0.12065 -0.2794)
			(stroke
				(width 0.1)
				(type default)
			)
			(layer "F.Fab")
		)
		(fp_line
			(start -0.67945 -0.305054)
			(end -0.12065 -0.305054)
			(stroke
				(width 0.1)
				(type default)
			)
			(layer "F.Fab")
		)
		(fp_line
			(start 0.67945 -0.3048)
			(end 0.67945 0.3048)
			(stroke
				(width 0.1)
				(type default)
			)
			(layer "F.Fab")
		)
		(fp_line
			(start 0.12065 -0.3048)
			(end 0.67945 -0.3048)
			(stroke
				(width 0.1)
				(type default)
			)
			(layer "F.Fab")
		)
		(fp_line
			(start 0.12065 -0.2794)
			(end 0.12065 -0.3048)
			(stroke
				(width 0.1)
				(type default)
			)
			(layer "F.Fab")
		)
		(fp_line
			(start -0.12065 -0.2794)
			(end 0.12065 -0.2794)
			(stroke
				(width 0.1)
				(type default)
			)
			(layer "F.Fab")
		)
		(fp_line
			(start 0.120396 0.2794)
			(end -0.12065 0.2794)
			(stroke
				(width 0.1)
				(type default)
			)
			(layer "F.Fab")
		)
		(fp_line
			(start -0.12065 0.2794)
			(end -0.12065 0.3048)
			(stroke
				(width 0.1)
				(type default)
			)
			(layer "F.Fab")
		)
		(fp_line
			(start 0.67945 0.3048)
			(end 0.120396 0.3048)
			(stroke
				(width 0.1)
				(type default)
			)
			(layer "F.Fab")
		)
		(fp_line
			(start 0.120396 0.3048)
			(end 0.120396 0.2794)
			(stroke
				(width 0.1)
				(type default)
			)
			(layer "F.Fab")
		)
		(fp_line
			(start -0.12065 0.3048)
			(end -0.67945 0.3048)
			(stroke
				(width 0.1)
				(type default)
			)
			(layer "F.Fab")
		)
		(fp_line
			(start -0.67945 0.3048)
			(end -0.67945 -0.305054)
			(stroke
				(width 0.1)
				(type default)
			)
			(layer "F.Fab")
		)
		(pad "1" smd circle
			(at -0.40005 0 90)
			(size 0 0)
			(layers "F.Cu" "F.Mask" "F.Paste")
			(net "P3V3")
		)
		(pad "2" smd circle
			(at 0.40005 0 90)
			(size 0 0)
			(layers "F.Cu" "F.Mask" "F.Paste")
			(net "H_CPU0_MEMHOT_OUT_VT_N")
		)
	)
	(footprint ""
		(layer "F.Cu")
		(at 81.650078 -402.371052 -90)
		(property "Reference" "C732"
			(at 0 0 270)
			(layer "F.SilkS")
			(hide yes)
			(effects
				(font
					(size 1.27 1.27)
				)
			)
		)
		(property "Value" ""
			(at 0 0 270)
			(layer "F.Fab")
			(effects
				(font
					(size 1.27 1.27)
				)
			)
		)
		(duplicate_pad_numbers_are_jumpers no)
		(fp_line
			(start -0.299974 0.150114)
			(end -0.299974 -0.150114)
			(stroke
				(width 0.1)
				(type default)
			)
			(layer "F.Fab")
		)
		(fp_line
			(start 0.299974 0.150114)
			(end -0.299974 0.150114)
			(stroke
				(width 0.1)
				(type default)
			)
			(layer "F.Fab")
		)
		(fp_line
			(start -0.299974 -0.150114)
			(end 0.299974 -0.150114)
			(stroke
				(width 0.1)
				(type default)
			)
			(layer "F.Fab")
		)
		(fp_line
			(start 0.299974 -0.150114)
			(end 0.299974 0.150114)
			(stroke
				(width 0.1)
				(type default)
			)
			(layer "F.Fab")
		)
		(pad "1" smd rect
			(at -0.2667 0 270)
			(size 0.3048 0.381)
			(layers "F.Cu" "F.Mask" "F.Paste")
			(net "P5E_CPU1_PE0_TX_C_DN<4>")
		)
		(pad "2" smd rect
			(at 0.2667 0 270)
			(size 0.3048 0.381)
			(layers "F.Cu" "F.Mask" "F.Paste")
			(net "P5E_CPU1_PE0_TX_DN<4>")
		)
	)
	(footprint ""
		(layer "F.Cu")
		(at 152.76322 -116.506752)
		(property "Reference" "R2343"
			(at 0 0 0)
			(layer "F.SilkS")
			(hide yes)
			(effects
				(font
					(size 1.27 1.27)
				)
			)
		)
		(property "Value" ""
			(at 0 0 0)
			(layer "F.Fab")
			(effects
				(font
					(size 1.27 1.27)
				)
			)
		)
		(duplicate_pad_numbers_are_jumpers no)
		(fp_line
			(start -0.7874 -0.4064)
			(end 0.7874 -0.4064)
			(stroke
				(width 0.1524)
				(type default)
			)
			(layer "F.SilkS")
		)
		(fp_line
			(start -0.7874 0.4064)
			(end -0.7874 -0.4064)
			(stroke
				(width 0.1524)
				(type default)
			)
			(layer "F.SilkS")
		)
		(fp_line
			(start 0.7874 -0.4064)
			(end 0.7874 0.4064)
			(stroke
				(width 0.1524)
				(type default)
			)
			(layer "F.SilkS")
		)
		(fp_line
			(start 0.7874 0.4064)
			(end -0.7874 0.4064)
			(stroke
				(width 0.1524)
				(type default)
			)
			(layer "F.SilkS")
		)
		(fp_line
			(start -0.67945 -0.305054)
			(end -0.12065 -0.305054)
			(stroke
				(width 0.1)
				(type default)
			)
			(layer "F.Fab")
		)
		(fp_line
			(start -0.67945 0.3048)
			(end -0.67945 -0.305054)
			(stroke
				(width 0.1)
				(type default)
			)
			(layer "F.Fab")
		)
		(fp_line
			(start -0.12065 -0.305054)
			(end -0.12065 -0.2794)
			(stroke
				(width 0.1)
				(type default)
			)
			(layer "F.Fab")
		)
		(fp_line
			(start -0.12065 -0.2794)
			(end 0.12065 -0.2794)
			(stroke
				(width 0.1)
				(type default)
			)
			(layer "F.Fab")
		)
		(fp_line
			(start -0.12065 0.2794)
			(end -0.12065 0.3048)
			(stroke
				(width 0.1)
				(type default)
			)
			(layer "F.Fab")
		)
		(fp_line
			(start -0.12065 0.3048)
			(end -0.67945 0.3048)
			(stroke
				(width 0.1)
				(type default)
			)
			(layer "F.Fab")
		)
		(fp_line
			(start 0.120396 0.2794)
			(end -0.12065 0.2794)
			(stroke
				(width 0.1)
				(type default)
			)
			(layer "F.Fab")
		)
		(fp_line
			(start 0.120396 0.3048)
			(end 0.120396 0.2794)
			(stroke
				(width 0.1)
				(type default)
			)
			(layer "F.Fab")
		)
		(fp_line
			(start 0.12065 -0.3048)
			(end 0.67945 -0.3048)
			(stroke
				(width 0.1)
				(type default)
			)
			(layer "F.Fab")
		)
		(fp_line
			(start 0.12065 -0.2794)
			(end 0.12065 -0.3048)
			(stroke
				(width 0.1)
				(type default)
			)
			(layer "F.Fab")
		)
		(fp_line
			(start 0.67945 -0.3048)
			(end 0.67945 0.3048)
			(stroke
				(width 0.1)
				(type default)
			)
			(layer "F.Fab")
		)
		(fp_line
			(start 0.67945 0.3048)
			(end 0.120396 0.3048)
			(stroke
				(width 0.1)
				(type default)
			)
			(layer "F.Fab")
		)
		(pad "1" smd circle
			(at -0.40005 0)
			(size 0 0)
			(layers "F.Cu" "F.Mask" "F.Paste")
			(net "P5V_AUX_VCC")
		)
		(pad "2" smd circle
			(at 0.40005 0)
			(size 0 0)
			(layers "F.Cu" "F.Mask" "F.Paste")
			(net "PWRGD_P5V_AUX")
		)
	)
	(footprint ""
		(layer "F.Cu")
		(at 241.295428 -108.743496 180)
		(property "Reference" "R1014"
			(at 0 0 180)
			(layer "F.SilkS")
			(hide yes)
			(effects
				(font
					(size 1.27 1.27)
				)
			)
		)
		(property "Value" ""
			(at 0 0 180)
			(layer "F.Fab")
			(effects
				(font
					(size 1.27 1.27)
				)
			)
		)
		(duplicate_pad_numbers_are_jumpers no)
		(fp_line
			(start 0.7874 0.4064)
			(end -0.7874 0.4064)
			(stroke
				(width 0.1524)
				(type default)
			)
			(layer "F.SilkS")
		)
		(fp_line
			(start 0.7874 -0.4064)
			(end 0.7874 0.4064)
			(stroke
				(width 0.1524)
				(type default)
			)
			(layer "F.SilkS")
		)
		(fp_line
			(start -0.7874 0.4064)
			(end -0.7874 -0.4064)
			(stroke
				(width 0.1524)
				(type default)
			)
			(layer "F.SilkS")
		)
		(fp_line
			(start -0.7874 -0.4064)
			(end 0.7874 -0.4064)
			(stroke
				(width 0.1524)
				(type default)
			)
			(layer "F.SilkS")
		)
		(fp_line
			(start 0.67945 0.3048)
			(end 0.120396 0.3048)
			(stroke
				(width 0.1)
				(type default)
			)
			(layer "F.Fab")
		)
		(fp_line
			(start 0.67945 -0.3048)
			(end 0.67945 0.3048)
			(stroke
				(width 0.1)
				(type default)
			)
			(layer "F.Fab")
		)
		(fp_line
			(start 0.12065 -0.2794)
			(end 0.12065 -0.3048)
			(stroke
				(width 0.1)
				(type default)
			)
			(layer "F.Fab")
		)
		(fp_line
			(start 0.12065 -0.3048)
			(end 0.67945 -0.3048)
			(stroke
				(width 0.1)
				(type default)
			)
			(layer "F.Fab")
		)
		(fp_line
			(start 0.120396 0.3048)
			(end 0.120396 0.2794)
			(stroke
				(width 0.1)
				(type default)
			)
			(layer "F.Fab")
		)
		(fp_line
			(start 0.120396 0.2794)
			(end -0.12065 0.2794)
			(stroke
				(width 0.1)
				(type default)
			)
			(layer "F.Fab")
		)
		(fp_line
			(start -0.12065 0.3048)
			(end -0.67945 0.3048)
			(stroke
				(width 0.1)
				(type default)
			)
			(layer "F.Fab")
		)
		(fp_line
			(start -0.12065 0.2794)
			(end -0.12065 0.3048)
			(stroke
				(width 0.1)
				(type default)
			)
			(layer "F.Fab")
		)
		(fp_line
			(start -0.12065 -0.2794)
			(end 0.12065 -0.2794)
			(stroke
				(width 0.1)
				(type default)
			)
			(layer "F.Fab")
		)
		(fp_line
			(start -0.12065 -0.305054)
			(end -0.12065 -0.2794)
			(stroke
				(width 0.1)
				(type default)
			)
			(layer "F.Fab")
		)
		(fp_line
			(start -0.67945 0.3048)
			(end -0.67945 -0.305054)
			(stroke
				(width 0.1)
				(type default)
			)
			(layer "F.Fab")
		)
		(fp_line
			(start -0.67945 -0.305054)
			(end -0.12065 -0.305054)
			(stroke
				(width 0.1)
				(type default)
			)
			(layer "F.Fab")
		)
		(pad "1" smd circle
			(at -0.40005 0 180)
			(size 0 0)
			(layers "F.Cu" "F.Mask" "F.Paste")
			(net "CLK_25M_CK440_CPU0_DN")
		)
		(pad "2" smd circle
			(at 0.40005 0 180)
			(size 0 0)
			(layers "F.Cu" "F.Mask" "F.Paste")
			(net "CLK_25M_CK440_CPU0_R_DN")
		)
	)
	(footprint ""
		(layer "F.Cu")
		(at 33.449006 -391.635996 180)
		(property "Reference" "R4658"
			(at 0 0 180)
			(layer "F.SilkS")
			(hide yes)
			(effects
				(font
					(size 1.27 1.27)
				)
			)
		)
		(property "Value" ""
			(at 0 0 180)
			(layer "F.Fab")
			(effects
				(font
					(size 1.27 1.27)
				)
			)
		)
		(duplicate_pad_numbers_are_jumpers no)
		(fp_line
			(start 0.7874 0.4064)
			(end -0.7874 0.4064)
			(stroke
				(width 0.1524)
				(type default)
			)
			(layer "F.SilkS")
		)
		(fp_line
			(start 0.7874 -0.4064)
			(end 0.7874 0.4064)
			(stroke
				(width 0.1524)
				(type default)
			)
			(layer "F.SilkS")
		)
		(fp_line
			(start -0.7874 0.4064)
			(end -0.7874 -0.4064)
			(stroke
				(width 0.1524)
				(type default)
			)
			(layer "F.SilkS")
		)
		(fp_line
			(start -0.7874 -0.4064)
			(end 0.7874 -0.4064)
			(stroke
				(width 0.1524)
				(type default)
			)
			(layer "F.SilkS")
		)
		(fp_line
			(start 0.67945 0.3048)
			(end 0.120396 0.3048)
			(stroke
				(width 0.1)
				(type default)
			)
			(layer "F.Fab")
		)
		(fp_line
			(start 0.67945 -0.3048)
			(end 0.67945 0.3048)
			(stroke
				(width 0.1)
				(type default)
			)
			(layer "F.Fab")
		)
		(fp_line
			(start 0.12065 -0.2794)
			(end 0.12065 -0.3048)
			(stroke
				(width 0.1)
				(type default)
			)
			(layer "F.Fab")
		)
		(fp_line
			(start 0.12065 -0.3048)
			(end 0.67945 -0.3048)
			(stroke
				(width 0.1)
				(type default)
			)
			(layer "F.Fab")
		)
		(fp_line
			(start 0.120396 0.3048)
			(end 0.120396 0.2794)
			(stroke
				(width 0.1)
				(type default)
			)
			(layer "F.Fab")
		)
		(fp_line
			(start 0.120396 0.2794)
			(end -0.12065 0.2794)
			(stroke
				(width 0.1)
				(type default)
			)
			(layer "F.Fab")
		)
		(fp_line
			(start -0.12065 0.3048)
			(end -0.67945 0.3048)
			(stroke
				(width 0.1)
				(type default)
			)
			(layer "F.Fab")
		)
		(fp_line
			(start -0.12065 0.2794)
			(end -0.12065 0.3048)
			(stroke
				(width 0.1)
				(type default)
			)
			(layer "F.Fab")
		)
		(fp_line
			(start -0.12065 -0.2794)
			(end 0.12065 -0.2794)
			(stroke
				(width 0.1)
				(type default)
			)
			(layer "F.Fab")
		)
		(fp_line
			(start -0.12065 -0.305054)
			(end -0.12065 -0.2794)
			(stroke
				(width 0.1)
				(type default)
			)
			(layer "F.Fab")
		)
		(fp_line
			(start -0.67945 0.3048)
			(end -0.67945 -0.305054)
			(stroke
				(width 0.1)
				(type default)
			)
			(layer "F.Fab")
		)
		(fp_line
			(start -0.67945 -0.305054)
			(end -0.12065 -0.305054)
			(stroke
				(width 0.1)
				(type default)
			)
			(layer "F.Fab")
		)
		(pad "1" smd circle
			(at -0.40005 0 180)
			(size 0 0)
			(layers "F.Cu" "F.Mask" "F.Paste")
			(net "FM_P2E_BUF2_VOD_SEL")
		)
		(pad "2" smd circle
			(at 0.40005 0 180)
			(size 0 0)
			(layers "F.Cu" "F.Mask" "F.Paste")
			(net "GND")
		)
	)
	(footprint ""
		(layer "F.Cu")
		(at 24.447754 -399.532094 90)
		(property "Reference" "R3282"
			(at 0 0 90)
			(layer "F.SilkS")
			(hide yes)
			(effects
				(font
					(size 1.27 1.27)
				)
			)
		)
		(property "Value" ""
			(at 0 0 90)
			(layer "F.Fab")
			(effects
				(font
					(size 1.27 1.27)
				)
			)
		)
		(duplicate_pad_numbers_are_jumpers no)
		(fp_line
			(start 0.7874 -0.4064)
			(end 0.7874 0.4064)
			(stroke
				(width 0.1524)
				(type default)
			)
			(layer "F.SilkS")
		)
		(fp_line
			(start -0.7874 -0.4064)
			(end 0.7874 -0.4064)
			(stroke
				(width 0.1524)
				(type default)
			)
			(layer "F.SilkS")
		)
		(fp_line
			(start 0.7874 0.4064)
			(end -0.7874 0.4064)
			(stroke
				(width 0.1524)
				(type default)
			)
			(layer "F.SilkS")
		)
		(fp_line
			(start -0.7874 0.4064)
			(end -0.7874 -0.4064)
			(stroke
				(width 0.1524)
				(type default)
			)
			(layer "F.SilkS")
		)
		(fp_line
			(start -0.12065 -0.305054)
			(end -0.12065 -0.2794)
			(stroke
				(width 0.1)
				(type default)
			)
			(layer "F.Fab")
		)
		(fp_line
			(start -0.67945 -0.305054)
			(end -0.12065 -0.305054)
			(stroke
				(width 0.1)
				(type default)
			)
			(layer "F.Fab")
		)
		(fp_line
			(start 0.67945 -0.3048)
			(end 0.67945 0.3048)
			(stroke
				(width 0.1)
				(type default)
			)
			(layer "F.Fab")
		)
		(fp_line
			(start 0.12065 -0.3048)
			(end 0.67945 -0.3048)
			(stroke
				(width 0.1)
				(type default)
			)
			(layer "F.Fab")
		)
		(fp_line
			(start 0.12065 -0.2794)
			(end 0.12065 -0.3048)
			(stroke
				(width 0.1)
				(type default)
			)
			(layer "F.Fab")
		)
		(fp_line
			(start -0.12065 -0.2794)
			(end 0.12065 -0.2794)
			(stroke
				(width 0.1)
				(type default)
			)
			(layer "F.Fab")
		)
		(fp_line
			(start 0.120396 0.2794)
			(end -0.12065 0.2794)
			(stroke
				(width 0.1)
				(type default)
			)
			(layer "F.Fab")
		)
		(fp_line
			(start -0.12065 0.2794)
			(end -0.12065 0.3048)
			(stroke
				(width 0.1)
				(type default)
			)
			(layer "F.Fab")
		)
		(fp_line
			(start 0.67945 0.3048)
			(end 0.120396 0.3048)
			(stroke
				(width 0.1)
				(type default)
			)
			(layer "F.Fab")
		)
		(fp_line
			(start 0.120396 0.3048)
			(end 0.120396 0.2794)
			(stroke
				(width 0.1)
				(type default)
			)
			(layer "F.Fab")
		)
		(fp_line
			(start -0.12065 0.3048)
			(end -0.67945 0.3048)
			(stroke
				(width 0.1)
				(type default)
			)
			(layer "F.Fab")
		)
		(fp_line
			(start -0.67945 0.3048)
			(end -0.67945 -0.305054)
			(stroke
				(width 0.1)
				(type default)
			)
			(layer "F.Fab")
		)
		(pad "1" smd circle
			(at -0.40005 0 90)
			(size 0 0)
			(layers "F.Cu" "F.Mask" "F.Paste")
			(net "FM_P2E_EQB0")
		)
		(pad "2" smd circle
			(at 0.40005 0 90)
			(size 0 0)
			(layers "F.Cu" "F.Mask" "F.Paste")
			(net "GND")
		)
	)
)
